(kicad_pcb
	(version 20260206)
	(generator "pcbnew")
	(generator_version "10.0")
	(general
		(thickness 1.6)
		(legacy_teardrops no)
	)
	(paper "A4")
	(title_block
		(title "panther-plus-userver — 13130-1b_20150205.brd")
		(comment 1 "Honey Badger (Wiwynn) / footprints 409-416 of 1509")
	)
	(layers
		(0 "F.Cu" signal "TOP")
		(4 "In1.Cu" signal "L2")
		(6 "In2.Cu" signal "L3")
		(8 "In3.Cu" signal "L4")
		(10 "In4.Cu" signal "L5")
		(12 "In5.Cu" signal "L6")
		(14 "In6.Cu" signal "L7")
		(16 "In7.Cu" signal "L8")
		(18 "In8.Cu" signal "L9")
		(20 "In9.Cu" signal "L10")
		(22 "In10.Cu" signal "L11")
		(2 "B.Cu" signal "BOTTOM")
		(9 "F.Adhes" user "F.Adhesive")
		(11 "B.Adhes" user "B.Adhesive")
		(13 "F.Paste" user "Package Geometry/Pastemask Top")
		(15 "B.Paste" user "Package Geometry/Pastemask Bottom")
		(5 "F.SilkS" user "Ref Des/Silkscreen Top")
		(7 "B.SilkS" user "Ref Des/Silkscreen Bottom")
		(1 "F.Mask" user "Board Geometry/Soldermask Top")
		(3 "B.Mask" user "Board Geometry/Soldermask Bottom")
		(17 "Dwgs.User" user "User.Drawings")
		(19 "Cmts.User" user "User.Comments")
		(21 "Eco1.User" user "User.Eco1")
		(23 "Eco2.User" user "User.Eco2")
		(25 "Edge.Cuts" user "Board Geometry/Outline")
		(27 "Margin" user)
		(31 "F.CrtYd" user "Package Geometry/Place Bound Top")
		(29 "B.CrtYd" user "Package Geometry/Place Bound Bottom")
		(35 "F.Fab" user "Ref Des/Assembly Top")
		(33 "B.Fab" user "Ref Des/Assembly Bottom")
	)
	(footprint ""
		(layer "F.Cu")
		(at 45.4152 -51.3334)
		(property "Reference" "C51"
			(at 0 0 0)
			(layer "F.SilkS")
			(hide yes)
			(effects
				(font
					(size 1.27 1.27)
				)
			)
		)
		(property "Value" "SCD1U10V2KX-5GP"
			(at 1.8923 -1.2065 0)
			(unlocked yes)
			(layer "F.Fab")
			(hide yes)
			(effects
				(font
					(size 1.016 1.016)
					(thickness 0.1524)
				)
			)
		)
		(property "Device Type" "C402H22"
			(at 1.8923 -2.7305 0)
			(unlocked yes)
			(layer "F.Fab")
			(hide yes)
			(effects
				(font
					(size 1.016 1.016)
					(thickness 0.1524)
				)
			)
		)
		(duplicate_pad_numbers_are_jumpers no)
		(fp_rect
			(start -0.381 0.7366)
			(end 0.381 -0.7366)
			(stroke
				(width 0)
				(type default)
			)
			(fill no)
			(layer "F.CrtYd")
		)
		(fp_rect
			(start -0.381 0.7366)
			(end 0.381 -0.7366)
			(stroke
				(width 0)
				(type default)
			)
			(fill no)
			(layer "F.Fab")
		)
		(pad "1" smd custom
			(at 0 -0.4572)
			(size 0.1143 0.1143)
			(layers "F.Cu" "F.Mask" "F.Paste")
			(net "P3V3_CLK_VDD25")
			(options
				(clearance outline)
				(anchor circle)
			)
			(primitives
				(gr_poly
					(pts
						(arc
							(start -0.254 -0.1778)
							(mid -0.239121 -0.213721)
							(end -0.2032 -0.2286)
						)
						(arc
							(start 0.2032 -0.2286)
							(mid 0.239121 -0.213721)
							(end 0.254 -0.1778)
						)
						(arc
							(start 0.254 0.1778)
							(mid 0.239121 0.213721)
							(end 0.2032 0.2286)
						)
						(arc
							(start -0.2032 0.2286)
							(mid -0.239121 0.213721)
							(end -0.254 0.1778)
						)
					)
					(width 0)
					(fill yes)
				)
			)
		)
		(pad "2" smd custom
			(at 0 0.4572)
			(size 0.1143 0.1143)
			(layers "F.Cu" "F.Mask" "F.Paste")
			(net "GND")
			(options
				(clearance outline)
				(anchor circle)
			)
			(primitives
				(gr_poly
					(pts
						(arc
							(start -0.254 -0.1778)
							(mid -0.239121 -0.213721)
							(end -0.2032 -0.2286)
						)
						(arc
							(start 0.2032 -0.2286)
							(mid 0.239121 -0.213721)
							(end 0.254 -0.1778)
						)
						(arc
							(start 0.254 0.1778)
							(mid 0.239121 0.213721)
							(end 0.2032 0.2286)
						)
						(arc
							(start -0.2032 0.2286)
							(mid -0.239121 0.213721)
							(end -0.254 0.1778)
						)
					)
					(width 0)
					(fill yes)
				)
			)
		)
	)
	(footprint ""
		(layer "F.Cu")
		(at 198.12 -5.588 -90)
		(property "Reference" "R390"
			(at 0 0 270)
			(layer "F.SilkS")
			(hide yes)
			(effects
				(font
					(size 1.27 1.27)
				)
			)
		)
		(property "Value" "4K7R2F-GP"
			(at 0.064008 -3.993896 270)
			(unlocked yes)
			(layer "F.Fab")
			(hide yes)
			(effects
				(font
					(size 1.016 1.016)
					(thickness 0.1524)
				)
			)
		)
		(property "Device Type" "R402H16"
			(at 0.064008 -5.517896 270)
			(unlocked yes)
			(layer "F.Fab")
			(hide yes)
			(effects
				(font
					(size 1.016 1.016)
					(thickness 0.1524)
				)
			)
		)
		(duplicate_pad_numbers_are_jumpers no)
		(fp_rect
			(start -0.381 0.8382)
			(end 0.381 -0.8382)
			(stroke
				(width 0)
				(type default)
			)
			(fill no)
			(layer "F.CrtYd")
		)
		(fp_rect
			(start -0.381 0.8382)
			(end 0.381 -0.8382)
			(stroke
				(width 0)
				(type default)
			)
			(fill no)
			(layer "F.Fab")
		)
		(pad "1" smd custom
			(at 0 -0.4318 270)
			(size 0.127 0.127)
			(layers "F.Cu" "F.Mask" "F.Paste")
			(net "P3V3_STBY")
			(options
				(clearance outline)
				(anchor circle)
			)
			(primitives
				(gr_poly
					(pts
						(arc
							(start -0.2032 -0.2794)
							(mid -0.239121 -0.264521)
							(end -0.254 -0.2286)
						)
						(arc
							(start -0.254 0.2286)
							(mid -0.239121 0.264521)
							(end -0.2032 0.2794)
						)
						(arc
							(start 0.2032 0.2794)
							(mid 0.239121 0.264521)
							(end 0.254 0.2286)
						)
						(arc
							(start 0.254 -0.2286)
							(mid 0.239121 -0.264521)
							(end 0.2032 -0.2794)
						)
					)
					(width 0)
					(fill yes)
				)
			)
		)
		(pad "2" smd custom
			(at 0 0.4318 270)
			(size 0.127 0.127)
			(layers "F.Cu" "F.Mask" "F.Paste")
			(net "CHB_1_SA1")
			(options
				(clearance outline)
				(anchor circle)
			)
			(primitives
				(gr_poly
					(pts
						(arc
							(start -0.2032 -0.2794)
							(mid -0.239121 -0.264521)
							(end -0.254 -0.2286)
						)
						(arc
							(start -0.254 0.2286)
							(mid -0.239121 0.264521)
							(end -0.2032 0.2794)
						)
						(arc
							(start 0.2032 0.2794)
							(mid 0.239121 0.264521)
							(end 0.254 0.2286)
						)
						(arc
							(start 0.254 -0.2286)
							(mid 0.239121 -0.264521)
							(end 0.2032 -0.2794)
						)
					)
					(width 0)
					(fill yes)
				)
			)
		)
	)
	(footprint ""
		(layer "F.Cu")
		(at 60.9854 -29.0322 90)
		(property "Reference" "Q8"
			(at 0 0 90)
			(layer "F.SilkS")
			(hide yes)
			(effects
				(font
					(size 1.27 1.27)
				)
			)
		)
		(property "Value" "FDN359BN-GP-U"
			(at -3.175 0.254 90)
			(unlocked yes)
			(layer "F.Fab")
			(hide yes)
			(effects
				(font
					(size 1.016 1.016)
					(thickness 0.1524)
				)
			)
		)
		(property "Device Type" "SOT23DGS2D6H45"
			(at -3.175 -1.27 90)
			(unlocked yes)
			(layer "F.Fab")
			(hide yes)
			(effects
				(font
					(size 1.016 1.016)
					(thickness 0.1524)
				)
			)
		)
		(duplicate_pad_numbers_are_jumpers no)
		(fp_line
			(start 1.7145 -0.2794)
			(end -1.7145 -0.2794)
			(stroke
				(width 0.1524)
				(type default)
			)
			(layer "F.SilkS")
		)
		(fp_line
			(start -1.7145 -0.2794)
			(end -1.7145 0.2794)
			(stroke
				(width 0.1524)
				(type default)
			)
			(layer "F.SilkS")
		)
		(fp_line
			(start 1.7145 0.2794)
			(end 1.7145 -0.2794)
			(stroke
				(width 0.1524)
				(type default)
			)
			(layer "F.SilkS")
		)
		(fp_line
			(start -1.7145 0.2794)
			(end 1.7145 0.2794)
			(stroke
				(width 0.1524)
				(type default)
			)
			(layer "F.SilkS")
		)
		(fp_rect
			(start -1.7145 1.651)
			(end 1.7145 -1.651)
			(stroke
				(width 0)
				(type default)
			)
			(fill no)
			(layer "F.CrtYd")
		)
		(fp_rect
			(start -1.7145 1.651)
			(end 1.7145 -1.651)
			(stroke
				(width 0)
				(type default)
			)
			(fill no)
			(layer "F.Fab")
		)
		(pad "D" smd custom
			(at 0 -1.016 90)
			(size 0.1651 0.1651)
			(layers "F.Cu" "F.Mask" "F.Paste")
			(net "P1V8_STBY")
			(options
				(clearance outline)
				(anchor circle)
			)
			(primitives
				(gr_poly
					(pts
						(arc
							(start -0.127 0.508)
							(mid -0.270684 0.448484)
							(end -0.3302 0.3048)
						)
						(arc
							(start -0.3302 -0.3048)
							(mid -0.270684 -0.448484)
							(end -0.127 -0.508)
						)
						(arc
							(start 0.127 -0.508)
							(mid 0.270684 -0.448484)
							(end 0.3302 -0.3048)
						)
						(arc
							(start 0.3302 0.3048)
							(mid 0.270684 0.448484)
							(end 0.127 0.508)
						)
					)
					(width 0)
					(fill yes)
				)
			)
		)
		(pad "G" smd custom
			(at -0.94996 1.016 90)
			(size 0.1651 0.1651)
			(layers "F.Cu" "F.Mask" "F.Paste")
			(net "SW_P1V8_EN_LV")
			(options
				(clearance outline)
				(anchor circle)
			)
			(primitives
				(gr_poly
					(pts
						(arc
							(start -0.127 0.508)
							(mid -0.270684 0.448484)
							(end -0.3302 0.3048)
						)
						(arc
							(start -0.3302 -0.3048)
							(mid -0.270684 -0.448484)
							(end -0.127 -0.508)
						)
						(arc
							(start 0.127 -0.508)
							(mid 0.270684 -0.448484)
							(end 0.3302 -0.3048)
						)
						(arc
							(start 0.3302 0.3048)
							(mid 0.270684 0.448484)
							(end 0.127 0.508)
						)
					)
					(width 0)
					(fill yes)
				)
			)
		)
		(pad "S" smd custom
			(at 0.94996 1.016 90)
			(size 0.1651 0.1651)
			(layers "F.Cu" "F.Mask" "F.Paste")
			(net "P1V8")
			(options
				(clearance outline)
				(anchor circle)
			)
			(primitives
				(gr_poly
					(pts
						(arc
							(start -0.127 0.508)
							(mid -0.270684 0.448484)
							(end -0.3302 0.3048)
						)
						(arc
							(start -0.3302 -0.3048)
							(mid -0.270684 -0.448484)
							(end -0.127 -0.508)
						)
						(arc
							(start 0.127 -0.508)
							(mid 0.270684 -0.448484)
							(end 0.3302 -0.3048)
						)
						(arc
							(start 0.3302 0.3048)
							(mid 0.270684 0.448484)
							(end 0.127 0.508)
						)
					)
					(width 0)
					(fill yes)
				)
			)
		)
	)
	(footprint ""
		(layer "F.Cu")
		(at 140.843 -59.944 90)
		(property "Reference" "PC40"
			(at 0 0 90)
			(layer "F.SilkS")
			(hide yes)
			(effects
				(font
					(size 1.27 1.27)
				)
			)
		)
		(property "Value" "SC4D7U10V3KX-GP"
			(at 0 -2.8194 90)
			(unlocked yes)
			(layer "F.Fab")
			(hide yes)
			(effects
				(font
					(size 1.016 1.016)
					(thickness 0.1524)
				)
			)
		)
		(property "Device Type" "C603H36"
			(at 0 -4.3434 90)
			(unlocked yes)
			(layer "F.Fab")
			(hide yes)
			(effects
				(font
					(size 1.016 1.016)
					(thickness 0.1524)
				)
			)
		)
		(duplicate_pad_numbers_are_jumpers no)
		(fp_line
			(start -0.4064 0)
			(end 0.4064 0)
			(stroke
				(width 0.2286)
				(type default)
			)
			(layer "F.SilkS")
		)
		(fp_rect
			(start -0.635 1.1811)
			(end 0.635 -1.1811)
			(stroke
				(width 0)
				(type default)
			)
			(fill no)
			(layer "F.CrtYd")
		)
		(fp_rect
			(start -0.635 1.1811)
			(end 0.635 -1.1811)
			(stroke
				(width 0)
				(type default)
			)
			(fill no)
			(layer "F.Fab")
		)
		(pad "1" smd custom
			(at 0 -0.6604 90)
			(size 0.19685 0.19685)
			(layers "F.Cu" "F.Mask" "F.Paste")
			(net "PV_VTT_DDR_VIN")
			(options
				(clearance outline)
				(anchor circle)
			)
			(primitives
				(gr_poly
					(pts
						(arc
							(start 0.508 -0.2921)
							(mid 0.478242 -0.363942)
							(end 0.4064 -0.3937)
						)
						(arc
							(start -0.4064 -0.3937)
							(mid -0.478242 -0.363942)
							(end -0.508 -0.2921)
						)
						(arc
							(start -0.508 0.2921)
							(mid -0.478242 0.363942)
							(end -0.4064 0.3937)
						)
						(arc
							(start 0.4064 0.3937)
							(mid 0.478242 0.363942)
							(end 0.508 0.2921)
						)
					)
					(width 0)
					(fill yes)
				)
			)
		)
		(pad "2" smd custom
			(at 0 0.6604 90)
			(size 0.19685 0.19685)
			(layers "F.Cu" "F.Mask" "F.Paste")
			(net "GND")
			(options
				(clearance outline)
				(anchor circle)
			)
			(primitives
				(gr_poly
					(pts
						(arc
							(start 0.508 -0.2921)
							(mid 0.478242 -0.363942)
							(end 0.4064 -0.3937)
						)
						(arc
							(start -0.4064 -0.3937)
							(mid -0.478242 -0.363942)
							(end -0.508 -0.2921)
						)
						(arc
							(start -0.508 0.2921)
							(mid -0.478242 0.363942)
							(end -0.4064 0.3937)
						)
						(arc
							(start 0.4064 0.3937)
							(mid 0.478242 0.363942)
							(end 0.508 0.2921)
						)
					)
					(width 0)
					(fill yes)
				)
			)
		)
	)
	(footprint ""
		(layer "F.Cu")
		(at 189.611 -39.497 90)
		(property "Reference" "PC87"
			(at 0 0 90)
			(layer "F.SilkS")
			(hide yes)
			(effects
				(font
					(size 1.27 1.27)
				)
			)
		)
		(property "Value" "SC1000P50V-N8-GP"
			(at 1.8923 -1.2065 90)
			(unlocked yes)
			(layer "F.Fab")
			(hide yes)
			(effects
				(font
					(size 1.016 1.016)
					(thickness 0.1524)
				)
			)
		)
		(property "Device Type" "C402H22"
			(at 1.8923 -2.7305 90)
			(unlocked yes)
			(layer "F.Fab")
			(hide yes)
			(effects
				(font
					(size 1.016 1.016)
					(thickness 0.1524)
				)
			)
		)
		(duplicate_pad_numbers_are_jumpers no)
		(fp_rect
			(start -0.381 0.7366)
			(end 0.381 -0.7366)
			(stroke
				(width 0)
				(type default)
			)
			(fill no)
			(layer "F.CrtYd")
		)
		(fp_rect
			(start -0.381 0.7366)
			(end 0.381 -0.7366)
			(stroke
				(width 0)
				(type default)
			)
			(fill no)
			(layer "F.Fab")
		)
		(pad "1" smd custom
			(at 0 -0.4572 90)
			(size 0.1143 0.1143)
			(layers "F.Cu" "F.Mask" "F.Paste")
			(net "VR_PVDDR_A_VAUTO")
			(options
				(clearance outline)
				(anchor circle)
			)
			(primitives
				(gr_poly
					(pts
						(arc
							(start -0.254 -0.1778)
							(mid -0.239121 -0.213721)
							(end -0.2032 -0.2286)
						)
						(arc
							(start 0.2032 -0.2286)
							(mid 0.239121 -0.213721)
							(end 0.254 -0.1778)
						)
						(arc
							(start 0.254 0.1778)
							(mid 0.239121 0.213721)
							(end 0.2032 0.2286)
						)
						(arc
							(start -0.2032 0.2286)
							(mid -0.239121 0.213721)
							(end -0.254 0.1778)
						)
					)
					(width 0)
					(fill yes)
				)
			)
		)
		(pad "2" smd custom
			(at 0 0.4572 90)
			(size 0.1143 0.1143)
			(layers "F.Cu" "F.Mask" "F.Paste")
			(net "GND")
			(options
				(clearance outline)
				(anchor circle)
			)
			(primitives
				(gr_poly
					(pts
						(arc
							(start -0.254 -0.1778)
							(mid -0.239121 -0.213721)
							(end -0.2032 -0.2286)
						)
						(arc
							(start 0.2032 -0.2286)
							(mid 0.239121 -0.213721)
							(end 0.254 -0.1778)
						)
						(arc
							(start 0.254 0.1778)
							(mid 0.239121 0.213721)
							(end 0.2032 0.2286)
						)
						(arc
							(start -0.2032 0.2286)
							(mid -0.239121 0.213721)
							(end -0.254 0.1778)
						)
					)
					(width 0)
					(fill yes)
				)
			)
		)
	)
	(footprint ""
		(layer "F.Cu")
		(at 49.085754 -53.3781 -90)
		(property "Reference" "L12"
			(at 0 0 270)
			(layer "F.SilkS")
			(hide yes)
			(effects
				(font
					(size 1.27 1.27)
				)
			)
		)
		(property "Value" "BLM18PG330SN1D-GP"
			(at -0.0254 -2.0193 270)
			(unlocked yes)
			(layer "F.Fab")
			(hide yes)
			(effects
				(font
					(size 1.016 1.016)
					(thickness 0.1524)
				)
			)
		)
		(property "Device Type" "L1608-UH38"
			(at -0.0254 -3.5433 270)
			(unlocked yes)
			(layer "F.Fab")
			(hide yes)
			(effects
				(font
					(size 1.016 1.016)
					(thickness 0.1524)
				)
			)
		)
		(duplicate_pad_numbers_are_jumpers no)
		(fp_line
			(start -0.4064 0)
			(end 0.4064 0)
			(stroke
				(width 0.2032)
				(type default)
			)
			(layer "F.SilkS")
		)
		(fp_rect
			(start -0.635 1.1811)
			(end 0.635 -1.1811)
			(stroke
				(width 0)
				(type default)
			)
			(fill no)
			(layer "F.CrtYd")
		)
		(fp_rect
			(start -0.635 1.1811)
			(end 0.635 -1.1811)
			(stroke
				(width 0)
				(type default)
			)
			(fill no)
			(layer "F.Fab")
		)
		(pad "1" smd custom
			(at 0 -0.6604 270)
			(size 0.19685 0.19685)
			(layers "F.Cu" "F.Mask" "F.Paste")
			(net "P1V5_STBY")
			(options
				(clearance outline)
				(anchor circle)
			)
			(primitives
				(gr_poly
					(pts
						(arc
							(start 0.508 -0.2921)
							(mid 0.478242 -0.363942)
							(end 0.4064 -0.3937)
						)
						(arc
							(start -0.4064 -0.3937)
							(mid -0.478242 -0.363942)
							(end -0.508 -0.2921)
						)
						(arc
							(start -0.508 0.2921)
							(mid -0.478242 0.363942)
							(end -0.4064 0.3937)
						)
						(arc
							(start 0.4064 0.3937)
							(mid 0.478242 0.363942)
							(end 0.508 0.2921)
						)
					)
					(width 0)
					(fill yes)
				)
			)
		)
		(pad "2" smd custom
			(at 0 0.6604 270)
			(size 0.19685 0.19685)
			(layers "F.Cu" "F.Mask" "F.Paste")
			(net "P1V5_CLK_VDD_CORE")
			(options
				(clearance outline)
				(anchor circle)
			)
			(primitives
				(gr_poly
					(pts
						(arc
							(start 0.508 -0.2921)
							(mid 0.478242 -0.363942)
							(end 0.4064 -0.3937)
						)
						(arc
							(start -0.4064 -0.3937)
							(mid -0.478242 -0.363942)
							(end -0.508 -0.2921)
						)
						(arc
							(start -0.508 0.2921)
							(mid -0.478242 0.363942)
							(end -0.4064 0.3937)
						)
						(arc
							(start 0.4064 0.3937)
							(mid 0.478242 0.363942)
							(end 0.508 0.2921)
						)
					)
					(width 0)
					(fill yes)
				)
			)
		)
	)
	(footprint ""
		(layer "F.Cu")
		(at 187.579 -45.974)
		(property "Reference" "R221"
			(at 0 0 0)
			(layer "F.SilkS")
			(hide yes)
			(effects
				(font
					(size 1.27 1.27)
				)
			)
		)
		(property "Value" "2D2R2J-GP"
			(at 0.064008 -3.993896 0)
			(unlocked yes)
			(layer "F.Fab")
			(hide yes)
			(effects
				(font
					(size 1.016 1.016)
					(thickness 0.1524)
				)
			)
		)
		(property "Device Type" "R402H16"
			(at 0.064008 -5.517896 0)
			(unlocked yes)
			(layer "F.Fab")
			(hide yes)
			(effects
				(font
					(size 1.016 1.016)
					(thickness 0.1524)
				)
			)
		)
		(duplicate_pad_numbers_are_jumpers no)
		(fp_rect
			(start -0.381 0.8382)
			(end 0.381 -0.8382)
			(stroke
				(width 0)
				(type default)
			)
			(fill no)
			(layer "F.CrtYd")
		)
		(fp_rect
			(start -0.381 0.8382)
			(end 0.381 -0.8382)
			(stroke
				(width 0)
				(type default)
			)
			(fill no)
			(layer "F.Fab")
		)
		(pad "1" smd custom
			(at 0 -0.4318)
			(size 0.127 0.127)
			(layers "F.Cu" "F.Mask" "F.Paste")
			(net "PV_VDDR_VREF_B_FB")
			(options
				(clearance outline)
				(anchor circle)
			)
			(primitives
				(gr_poly
					(pts
						(arc
							(start -0.2032 -0.2794)
							(mid -0.239121 -0.264521)
							(end -0.254 -0.2286)
						)
						(arc
							(start -0.254 0.2286)
							(mid -0.239121 0.264521)
							(end -0.2032 0.2794)
						)
						(arc
							(start 0.2032 0.2794)
							(mid 0.239121 0.264521)
							(end 0.254 0.2286)
						)
						(arc
							(start 0.254 -0.2286)
							(mid 0.239121 -0.264521)
							(end 0.2032 -0.2794)
						)
					)
					(width 0)
					(fill yes)
				)
			)
		)
		(pad "2" smd custom
			(at 0 0.4318)
			(size 0.127 0.127)
			(layers "F.Cu" "F.Mask" "F.Paste")
			(net "PV_VDDR_VREF_B")
			(options
				(clearance outline)
				(anchor circle)
			)
			(primitives
				(gr_poly
					(pts
						(arc
							(start -0.2032 -0.2794)
							(mid -0.239121 -0.264521)
							(end -0.254 -0.2286)
						)
						(arc
							(start -0.254 0.2286)
							(mid -0.239121 0.264521)
							(end -0.2032 0.2794)
						)
						(arc
							(start 0.2032 0.2794)
							(mid 0.239121 0.264521)
							(end 0.254 0.2286)
						)
						(arc
							(start 0.254 -0.2286)
							(mid 0.239121 -0.264521)
							(end 0.2032 -0.2794)
						)
					)
					(width 0)
					(fill yes)
				)
			)
		)
	)
	(footprint ""
		(layer "F.Cu")
		(at 15.0114 -65.786 90)
		(property "Reference" "C159"
			(at 0 0 90)
			(layer "F.SilkS")
			(hide yes)
			(effects
				(font
					(size 1.27 1.27)
				)
			)
		)
		(property "Value" "SC10U6D3V5KX-4GP"
			(at 0 -4.9022 90)
			(unlocked yes)
			(layer "F.Fab")
			(hide yes)
			(effects
				(font
					(size 1.016 1.016)
					(thickness 0.1524)
				)
			)
		)
		(property "Device Type" "C805H58"
			(at 0 -6.8072 90)
			(unlocked yes)
			(layer "F.Fab")
			(hide yes)
			(effects
				(font
					(size 1.016 1.016)
					(thickness 0.1524)
				)
			)
		)
		(duplicate_pad_numbers_are_jumpers no)
		(fp_line
			(start 0.6096 0)
			(end -0.6096 0)
			(stroke
				(width 0.3048)
				(type default)
			)
			(layer "F.SilkS")
		)
		(fp_poly
			(pts
				(xy -0.9017 1.4351) (xy 0.9017 1.4351) (xy 0.9017 -1.4351) (xy -0.9017 -1.4351)
			)
			(stroke
				(width 0)
				(type default)
			)
			(fill no)
			(layer "F.CrtYd")
		)
		(fp_poly
			(pts
				(xy 0.9017 1.4351) (xy 0.9017 -1.4351) (xy -0.9017 -1.4351) (xy -0.9017 1.4351)
			)
			(stroke
				(width 0)
				(type default)
			)
			(fill no)
			(layer "F.Fab")
		)
		(pad "1" smd rect
			(at 0 -0.8382 90)
			(size 1.5494 0.9398)
			(layers "F.Cu" "F.Mask" "F.Paste")
			(net "P3V3")
		)
		(pad "2" smd rect
			(at 0 0.8382 90)
			(size 1.5494 0.9398)
			(layers "F.Cu" "F.Mask" "F.Paste")
			(net "GND")
		)
	)
)
